(kicad_pcb
	(version 20260206)
	(generator "pcbnew")
	(generator_version "10.0")
	(general
		(thickness 1.6)
		(legacy_teardrops no)
	)
	(paper "A4")
	(title_block
		(title "04192023_DAF0TMB3IC0_F0TG_MB_C_brd_V02_OCP.brd")
		(comment 1 "Grand Teton / footprint 4934 of 8354 (J102), pads 114-226 of 291")
	)
	(layers
		(0 "F.Cu" signal "TOP")
		(4 "In1.Cu" signal "GND")
		(6 "In2.Cu" signal "IN1")
		(8 "In3.Cu" signal "GND1")
		(10 "In4.Cu" signal "IN2")
		(12 "In5.Cu" signal "GND2")
		(14 "In6.Cu" signal "IN3")
		(16 "In7.Cu" signal "GND3")
		(18 "In8.Cu" signal "VCC")
		(20 "In9.Cu" signal "VCC1")
		(22 "In10.Cu" signal "GND4")
		(24 "In11.Cu" signal "IN4")
		(26 "In12.Cu" signal "GND5")
		(28 "In13.Cu" signal "IN5")
		(30 "In14.Cu" signal "GND6")
		(32 "In15.Cu" signal "IN6")
		(34 "In16.Cu" signal "GND7")
		(2 "B.Cu" signal "BOTTOM")
		(9 "F.Adhes" user "F.Adhesive")
		(11 "B.Adhes" user "B.Adhesive")
		(13 "F.Paste" user "Package Geometry/Pastemask Top")
		(15 "B.Paste" user "Package Geometry/Pastemask Bottom")
		(5 "F.SilkS" user "Ref Des/Silkscreen Top")
		(7 "B.SilkS" user "Ref Des/Silkscreen Bottom")
		(1 "F.Mask" user "Board Geometry/Soldermask Top")
		(3 "B.Mask" user "Board Geometry/Soldermask Bottom")
		(17 "Dwgs.User" user "User.Drawings")
		(19 "Cmts.User" user "User.Comments")
		(21 "Eco1.User" user "User.Eco1")
		(23 "Eco2.User" user "User.Eco2")
		(25 "Edge.Cuts" user "Board Geometry/Outline")
		(27 "Margin" user)
		(31 "F.CrtYd" user "Package Geometry/Place Bound Top")
		(29 "B.CrtYd" user "Package Geometry/Place Bound Bottom")
		(35 "F.Fab" user "Ref Des/Assembly Top")
		(33 "B.Fab" user "Ref Des/Assembly Bottom")
	)
	(footprint ""
		(layer "F.Cu")
		(at 166.47795 -255.560322 180)
		(property "Reference" "J102"
			(at -2.7178 -81.857088 0)
			(unlocked yes)
			(layer "F.SilkS")
			(effects
				(font
					(size 0.7874 0.5842)
					(thickness 0.1524)
				)
			)
		)
		(property "Value" ""
			(at 0 0 180)
			(layer "F.Fab")
			(effects
				(font
					(size 1.27 1.27)
				)
			)
		)
		(duplicate_pad_numbers_are_jumpers no)
		(pad "114" smd rect
			(at -2.050034 37.824918 90)
			(size 0.519938 1.4986)
			(layers "F.Cu" "F.Mask" "F.Paste")
			(net "GND")
		)
		(pad "115" smd rect
			(at -2.050034 38.675056 90)
			(size 0.519938 1.4986)
			(layers "F.Cu" "F.Mask" "F.Paste")
			(net "M_G_CPU1_SB_DQS_DP<1>")
		)
		(pad "116" smd rect
			(at -2.050034 39.52494 90)
			(size 0.519938 1.4986)
			(layers "F.Cu" "F.Mask" "F.Paste")
			(net "M_G_CPU1_SB_DQS_DN<1>")
		)
		(pad "117" smd rect
			(at -2.050034 40.375078 90)
			(size 0.519938 1.4986)
			(layers "F.Cu" "F.Mask" "F.Paste")
			(net "GND")
		)
		(pad "118" smd rect
			(at -2.050034 41.224962 90)
			(size 0.519938 1.4986)
			(layers "F.Cu" "F.Mask" "F.Paste")
			(net "M_G_CPU1_SB_DQ<12>")
		)
		(pad "119" smd rect
			(at -2.050034 42.0751 90)
			(size 0.519938 1.4986)
			(layers "F.Cu" "F.Mask" "F.Paste")
			(net "GND")
		)
		(pad "120" smd rect
			(at -2.050034 42.924984 90)
			(size 0.519938 1.4986)
			(layers "F.Cu" "F.Mask" "F.Paste")
			(net "M_G_CPU1_SB_DQ<13>")
		)
		(pad "121" smd rect
			(at -2.050034 43.775122 90)
			(size 0.519938 1.4986)
			(layers "F.Cu" "F.Mask" "F.Paste")
			(net "GND")
		)
		(pad "122" smd rect
			(at -2.050034 44.625006 90)
			(size 0.519938 1.4986)
			(layers "F.Cu" "F.Mask" "F.Paste")
			(net "M_G_CPU1_SB_DQ<16>")
		)
		(pad "123" smd rect
			(at -2.050034 45.47489 90)
			(size 0.519938 1.4986)
			(layers "F.Cu" "F.Mask" "F.Paste")
			(net "GND")
		)
		(pad "124" smd rect
			(at -2.050034 46.325028 90)
			(size 0.519938 1.4986)
			(layers "F.Cu" "F.Mask" "F.Paste")
			(net "M_G_CPU1_SB_DQ<17>")
		)
		(pad "125" smd rect
			(at -2.050034 47.174912 90)
			(size 0.519938 1.4986)
			(layers "F.Cu" "F.Mask" "F.Paste")
			(net "GND")
		)
		(pad "126" smd rect
			(at -2.050034 48.02505 90)
			(size 0.519938 1.4986)
			(layers "F.Cu" "F.Mask" "F.Paste")
			(net "M_G_CPU1_SB_DQS_DP<2>")
		)
		(pad "127" smd rect
			(at -2.050034 48.874934 90)
			(size 0.519938 1.4986)
			(layers "F.Cu" "F.Mask" "F.Paste")
			(net "M_G_CPU1_SB_DQS_DN<2>")
		)
		(pad "128" smd rect
			(at -2.050034 49.725072 90)
			(size 0.519938 1.4986)
			(layers "F.Cu" "F.Mask" "F.Paste")
			(net "GND")
		)
		(pad "129" smd rect
			(at -2.050034 50.574956 90)
			(size 0.519938 1.4986)
			(layers "F.Cu" "F.Mask" "F.Paste")
			(net "M_G_CPU1_SB_DQ<20>")
		)
		(pad "130" smd rect
			(at -2.050034 51.425094 90)
			(size 0.519938 1.4986)
			(layers "F.Cu" "F.Mask" "F.Paste")
			(net "GND")
		)
		(pad "131" smd rect
			(at -2.050034 52.274978 90)
			(size 0.519938 1.4986)
			(layers "F.Cu" "F.Mask" "F.Paste")
			(net "M_G_CPU1_SB_DQ<21>")
		)
		(pad "132" smd rect
			(at -2.050034 53.125116 90)
			(size 0.519938 1.4986)
			(layers "F.Cu" "F.Mask" "F.Paste")
			(net "GND")
		)
		(pad "133" smd rect
			(at -2.050034 53.975 90)
			(size 0.519938 1.4986)
			(layers "F.Cu" "F.Mask" "F.Paste")
			(net "M_G_CPU1_SB_DQ<24>")
		)
		(pad "134" smd rect
			(at -2.050034 54.824884 90)
			(size 0.519938 1.4986)
			(layers "F.Cu" "F.Mask" "F.Paste")
			(net "GND")
		)
		(pad "135" smd rect
			(at -2.050034 55.675022 90)
			(size 0.519938 1.4986)
			(layers "F.Cu" "F.Mask" "F.Paste")
			(net "M_G_CPU1_SB_DQ<25>")
		)
		(pad "136" smd rect
			(at -2.050034 56.524906 90)
			(size 0.519938 1.4986)
			(layers "F.Cu" "F.Mask" "F.Paste")
			(net "GND")
		)
		(pad "137" smd rect
			(at -2.050034 57.375044 90)
			(size 0.519938 1.4986)
			(layers "F.Cu" "F.Mask" "F.Paste")
			(net "M_G_CPU1_SB_DQS_DP<3>")
		)
		(pad "138" smd rect
			(at -2.050034 58.224928 90)
			(size 0.519938 1.4986)
			(layers "F.Cu" "F.Mask" "F.Paste")
			(net "M_G_CPU1_SB_DQS_DN<3>")
		)
		(pad "139" smd rect
			(at -2.050034 59.075066 90)
			(size 0.519938 1.4986)
			(layers "F.Cu" "F.Mask" "F.Paste")
			(net "GND")
		)
		(pad "140" smd rect
			(at -2.050034 59.92495 90)
			(size 0.519938 1.4986)
			(layers "F.Cu" "F.Mask" "F.Paste")
			(net "M_G_CPU1_SB_DQ<28>")
		)
		(pad "141" smd rect
			(at -2.050034 60.775088 90)
			(size 0.519938 1.4986)
			(layers "F.Cu" "F.Mask" "F.Paste")
			(net "GND")
		)
		(pad "142" smd rect
			(at -2.050034 61.624972 90)
			(size 0.519938 1.4986)
			(layers "F.Cu" "F.Mask" "F.Paste")
			(net "M_G_CPU1_SB_DQ<29>")
		)
		(pad "143" smd rect
			(at -2.050034 62.47511 90)
			(size 0.519938 1.4986)
			(layers "F.Cu" "F.Mask" "F.Paste")
			(net "GND")
		)
		(pad "144" smd rect
			(at -2.050034 63.324994 90)
			(size 0.519938 1.4986)
			(layers "F.Cu" "F.Mask" "F.Paste")
			(net "Net_2341")
		)
		(pad "145" smd rect
			(at 2.050034 -63.324994 90)
			(size 0.519938 1.4986)
			(layers "F.Cu" "F.Mask" "F.Paste")
			(net "P12V_MEM_CPU1")
		)
		(pad "146" smd rect
			(at 2.050034 -62.47511 90)
			(size 0.519938 1.4986)
			(layers "F.Cu" "F.Mask" "F.Paste")
			(net "P12V_MEM_CPU1")
		)
		(pad "147" smd rect
			(at 2.050034 -61.624972 90)
			(size 0.519938 1.4986)
			(layers "F.Cu" "F.Mask" "F.Paste")
			(net "PWRGD_CHG_CPU1_DIMM0")
		)
		(pad "148" smd rect
			(at 2.050034 -60.775088 90)
			(size 0.519938 1.4986)
			(layers "F.Cu" "F.Mask" "F.Paste")
			(net "PD_CHG_CPU1_DIMM0_SAA")
		)
		(pad "149" smd rect
			(at 2.050034 -59.92495 90)
			(size 0.519938 1.4986)
			(layers "F.Cu" "F.Mask" "F.Paste")
			(net "Net_2342")
		)
		(pad "150" smd rect
			(at 2.050034 -59.075066 90)
			(size 0.519938 1.4986)
			(layers "F.Cu" "F.Mask" "F.Paste")
			(net "Net_2343")
		)
		(pad "151" smd rect
			(at 2.050034 -58.224928 90)
			(size 0.519938 1.4986)
			(layers "F.Cu" "F.Mask" "F.Paste")
			(net "GND")
		)
		(pad "152" smd rect
			(at 2.050034 -57.375044 90)
			(size 0.519938 1.4986)
			(layers "F.Cu" "F.Mask" "F.Paste")
			(net "M_G_CPU1_SA_DQ<2>")
		)
		(pad "153" smd rect
			(at 2.050034 -56.524906 90)
			(size 0.519938 1.4986)
			(layers "F.Cu" "F.Mask" "F.Paste")
			(net "GND")
		)
		(pad "154" smd rect
			(at 2.050034 -55.675022 90)
			(size 0.519938 1.4986)
			(layers "F.Cu" "F.Mask" "F.Paste")
			(net "M_G_CPU1_SA_DQ<3>")
		)
		(pad "155" smd rect
			(at 2.050034 -54.824884 90)
			(size 0.519938 1.4986)
			(layers "F.Cu" "F.Mask" "F.Paste")
			(net "GND")
		)
		(pad "156" smd rect
			(at 2.050034 -53.975 90)
			(size 0.519938 1.4986)
			(layers "F.Cu" "F.Mask" "F.Paste")
			(net "M_G_CPU1_SA_DQS_DN<5>")
		)
		(pad "157" smd rect
			(at 2.050034 -53.125116 90)
			(size 0.519938 1.4986)
			(layers "F.Cu" "F.Mask" "F.Paste")
			(net "M_G_CPU1_SA_DQS_DP<5>")
		)
		(pad "158" smd rect
			(at 2.050034 -52.274978 90)
			(size 0.519938 1.4986)
			(layers "F.Cu" "F.Mask" "F.Paste")
			(net "GND")
		)
		(pad "159" smd rect
			(at 2.050034 -51.425094 90)
			(size 0.519938 1.4986)
			(layers "F.Cu" "F.Mask" "F.Paste")
			(net "M_G_CPU1_SA_DQ<6>")
		)
		(pad "160" smd rect
			(at 2.050034 -50.574956 90)
			(size 0.519938 1.4986)
			(layers "F.Cu" "F.Mask" "F.Paste")
			(net "GND")
		)
		(pad "161" smd rect
			(at 2.050034 -49.725072 90)
			(size 0.519938 1.4986)
			(layers "F.Cu" "F.Mask" "F.Paste")
			(net "M_G_CPU1_SA_DQ<7>")
		)
		(pad "162" smd rect
			(at 2.050034 -48.874934 90)
			(size 0.519938 1.4986)
			(layers "F.Cu" "F.Mask" "F.Paste")
			(net "GND")
		)
		(pad "163" smd rect
			(at 2.050034 -48.02505 90)
			(size 0.519938 1.4986)
			(layers "F.Cu" "F.Mask" "F.Paste")
			(net "M_G_CPU1_SA_DQ<10>")
		)
		(pad "164" smd rect
			(at 2.050034 -47.174912 90)
			(size 0.519938 1.4986)
			(layers "F.Cu" "F.Mask" "F.Paste")
			(net "GND")
		)
		(pad "165" smd rect
			(at 2.050034 -46.325028 90)
			(size 0.519938 1.4986)
			(layers "F.Cu" "F.Mask" "F.Paste")
			(net "M_G_CPU1_SA_DQ<11>")
		)
		(pad "166" smd rect
			(at 2.050034 -45.47489 90)
			(size 0.519938 1.4986)
			(layers "F.Cu" "F.Mask" "F.Paste")
			(net "GND")
		)
		(pad "167" smd rect
			(at 2.050034 -44.625006 90)
			(size 0.519938 1.4986)
			(layers "F.Cu" "F.Mask" "F.Paste")
			(net "M_G_CPU1_SA_DQS_DN<6>")
		)
		(pad "168" smd rect
			(at 2.050034 -43.775122 90)
			(size 0.519938 1.4986)
			(layers "F.Cu" "F.Mask" "F.Paste")
			(net "M_G_CPU1_SA_DQS_DP<6>")
		)
		(pad "169" smd rect
			(at 2.050034 -42.924984 90)
			(size 0.519938 1.4986)
			(layers "F.Cu" "F.Mask" "F.Paste")
			(net "GND")
		)
		(pad "170" smd rect
			(at 2.050034 -42.0751 90)
			(size 0.519938 1.4986)
			(layers "F.Cu" "F.Mask" "F.Paste")
			(net "M_G_CPU1_SA_DQ<14>")
		)
		(pad "171" smd rect
			(at 2.050034 -41.224962 90)
			(size 0.519938 1.4986)
			(layers "F.Cu" "F.Mask" "F.Paste")
			(net "GND")
		)
		(pad "172" smd rect
			(at 2.050034 -40.375078 90)
			(size 0.519938 1.4986)
			(layers "F.Cu" "F.Mask" "F.Paste")
			(net "M_G_CPU1_SA_DQ<15>")
		)
		(pad "173" smd rect
			(at 2.050034 -39.52494 90)
			(size 0.519938 1.4986)
			(layers "F.Cu" "F.Mask" "F.Paste")
			(net "GND")
		)
		(pad "174" smd rect
			(at 2.050034 -38.675056 90)
			(size 0.519938 1.4986)
			(layers "F.Cu" "F.Mask" "F.Paste")
			(net "M_G_CPU1_SA_DQ<18>")
		)
		(pad "175" smd rect
			(at 2.050034 -37.824918 90)
			(size 0.519938 1.4986)
			(layers "F.Cu" "F.Mask" "F.Paste")
			(net "GND")
		)
		(pad "176" smd rect
			(at 2.050034 -36.975034 90)
			(size 0.519938 1.4986)
			(layers "F.Cu" "F.Mask" "F.Paste")
			(net "M_G_CPU1_SA_DQ<19>")
		)
		(pad "177" smd rect
			(at 2.050034 -36.124896 90)
			(size 0.519938 1.4986)
			(layers "F.Cu" "F.Mask" "F.Paste")
			(net "GND")
		)
		(pad "178" smd rect
			(at 2.050034 -35.275012 90)
			(size 0.519938 1.4986)
			(layers "F.Cu" "F.Mask" "F.Paste")
			(net "M_G_CPU1_SA_DQS_DN<7>")
		)
		(pad "179" smd rect
			(at 2.050034 -34.425128 90)
			(size 0.519938 1.4986)
			(layers "F.Cu" "F.Mask" "F.Paste")
			(net "M_G_CPU1_SA_DQS_DP<7>")
		)
		(pad "180" smd rect
			(at 2.050034 -33.57499 90)
			(size 0.519938 1.4986)
			(layers "F.Cu" "F.Mask" "F.Paste")
			(net "GND")
		)
		(pad "181" smd rect
			(at 2.050034 -32.725106 90)
			(size 0.519938 1.4986)
			(layers "F.Cu" "F.Mask" "F.Paste")
			(net "M_G_CPU1_SA_DQ<22>")
		)
		(pad "182" smd rect
			(at 2.050034 -31.874968 90)
			(size 0.519938 1.4986)
			(layers "F.Cu" "F.Mask" "F.Paste")
			(net "GND")
		)
		(pad "183" smd rect
			(at 2.050034 -31.025084 90)
			(size 0.519938 1.4986)
			(layers "F.Cu" "F.Mask" "F.Paste")
			(net "M_G_CPU1_SA_DQ<23>")
		)
		(pad "184" smd rect
			(at 2.050034 -30.174946 90)
			(size 0.519938 1.4986)
			(layers "F.Cu" "F.Mask" "F.Paste")
			(net "GND")
		)
		(pad "185" smd rect
			(at 2.050034 -29.325062 90)
			(size 0.519938 1.4986)
			(layers "F.Cu" "F.Mask" "F.Paste")
			(net "M_G_CPU1_SA_DQ<26>")
		)
		(pad "186" smd rect
			(at 2.050034 -28.474924 90)
			(size 0.519938 1.4986)
			(layers "F.Cu" "F.Mask" "F.Paste")
			(net "GND")
		)
		(pad "187" smd rect
			(at 2.050034 -27.62504 90)
			(size 0.519938 1.4986)
			(layers "F.Cu" "F.Mask" "F.Paste")
			(net "M_G_CPU1_SA_DQ<27>")
		)
		(pad "188" smd rect
			(at 2.050034 -26.774902 90)
			(size 0.519938 1.4986)
			(layers "F.Cu" "F.Mask" "F.Paste")
			(net "GND")
		)
		(pad "189" smd rect
			(at 2.050034 -25.925018 90)
			(size 0.519938 1.4986)
			(layers "F.Cu" "F.Mask" "F.Paste")
			(net "M_G_CPU1_SA_DQS_DN<8>")
		)
		(pad "190" smd rect
			(at 2.050034 -25.07488 90)
			(size 0.519938 1.4986)
			(layers "F.Cu" "F.Mask" "F.Paste")
			(net "M_G_CPU1_SA_DQS_DP<8>")
		)
		(pad "191" smd rect
			(at 2.050034 -24.224996 90)
			(size 0.519938 1.4986)
			(layers "F.Cu" "F.Mask" "F.Paste")
			(net "GND")
		)
		(pad "192" smd rect
			(at 2.050034 -23.375112 90)
			(size 0.519938 1.4986)
			(layers "F.Cu" "F.Mask" "F.Paste")
			(net "M_G_CPU1_SA_DQ<30>")
		)
		(pad "193" smd rect
			(at 2.050034 -22.524974 90)
			(size 0.519938 1.4986)
			(layers "F.Cu" "F.Mask" "F.Paste")
			(net "GND")
		)
		(pad "194" smd rect
			(at 2.050034 -21.67509 90)
			(size 0.519938 1.4986)
			(layers "F.Cu" "F.Mask" "F.Paste")
			(net "M_G_CPU1_SA_DQ<31>")
		)
		(pad "195" smd rect
			(at 2.050034 -20.824952 90)
			(size 0.519938 1.4986)
			(layers "F.Cu" "F.Mask" "F.Paste")
			(net "GND")
		)
		(pad "196" smd rect
			(at 2.050034 -19.975068 90)
			(size 0.519938 1.4986)
			(layers "F.Cu" "F.Mask" "F.Paste")
			(net "M_G_CPU1_SA_CB<2>")
		)
		(pad "197" smd rect
			(at 2.050034 -19.12493 90)
			(size 0.519938 1.4986)
			(layers "F.Cu" "F.Mask" "F.Paste")
			(net "GND")
		)
		(pad "198" smd rect
			(at 2.050034 -18.275046 90)
			(size 0.519938 1.4986)
			(layers "F.Cu" "F.Mask" "F.Paste")
			(net "M_G_CPU1_SA_CB<3>")
		)
		(pad "199" smd rect
			(at 2.050034 -17.424908 90)
			(size 0.519938 1.4986)
			(layers "F.Cu" "F.Mask" "F.Paste")
			(net "GND")
		)
		(pad "200" smd rect
			(at 2.050034 -16.575024 90)
			(size 0.519938 1.4986)
			(layers "F.Cu" "F.Mask" "F.Paste")
			(net "M_G_CPU1_SA_DQS_DN<9>")
		)
		(pad "201" smd rect
			(at 2.050034 -15.724886 90)
			(size 0.519938 1.4986)
			(layers "F.Cu" "F.Mask" "F.Paste")
			(net "M_G_CPU1_SA_DQS_DP<9>")
		)
		(pad "202" smd rect
			(at 2.050034 -14.875002 90)
			(size 0.519938 1.4986)
			(layers "F.Cu" "F.Mask" "F.Paste")
			(net "GND")
		)
		(pad "203" smd rect
			(at 2.050034 -14.025118 90)
			(size 0.519938 1.4986)
			(layers "F.Cu" "F.Mask" "F.Paste")
			(net "M_G_CPU1_SA_CB<6>")
		)
		(pad "204" smd rect
			(at 2.050034 -13.17498 90)
			(size 0.519938 1.4986)
			(layers "F.Cu" "F.Mask" "F.Paste")
			(net "GND")
		)
		(pad "205" smd rect
			(at 2.050034 -12.325096 90)
			(size 0.519938 1.4986)
			(layers "F.Cu" "F.Mask" "F.Paste")
			(net "M_G_CPU1_SA_CB<7>")
		)
		(pad "206" smd rect
			(at 2.050034 -11.474958 90)
			(size 0.519938 1.4986)
			(layers "F.Cu" "F.Mask" "F.Paste")
			(net "GND")
		)
		(pad "207" smd rect
			(at 2.050034 -10.625074 90)
			(size 0.519938 1.4986)
			(layers "F.Cu" "F.Mask" "F.Paste")
			(net "M_G_CPU1_RESET_N")
		)
		(pad "208" smd rect
			(at 2.050034 -9.774936 90)
			(size 0.519938 1.4986)
			(layers "F.Cu" "F.Mask" "F.Paste")
			(net "GND")
		)
		(pad "209" smd rect
			(at 2.050034 -8.925052 90)
			(size 0.519938 1.4986)
			(layers "F.Cu" "F.Mask" "F.Paste")
			(net "M_G_CPU1_SA_CS_N<1>")
		)
		(pad "210" smd rect
			(at 2.050034 -8.074914 90)
			(size 0.519938 1.4986)
			(layers "F.Cu" "F.Mask" "F.Paste")
			(net "GND")
		)
		(pad "211" smd rect
			(at 2.050034 -7.22503 90)
			(size 0.519938 1.4986)
			(layers "F.Cu" "F.Mask" "F.Paste")
			(net "M_G_CPU1_SA_CA<1>")
		)
		(pad "212" smd rect
			(at 2.050034 -6.374892 90)
			(size 0.519938 1.4986)
			(layers "F.Cu" "F.Mask" "F.Paste")
			(net "GND")
		)
		(pad "213" smd rect
			(at 2.050034 -5.525008 90)
			(size 0.519938 1.4986)
			(layers "F.Cu" "F.Mask" "F.Paste")
			(net "M_G_CPU1_SA_CA<3>")
		)
		(pad "214" smd rect
			(at 2.050034 -4.675124 90)
			(size 0.519938 1.4986)
			(layers "F.Cu" "F.Mask" "F.Paste")
			(net "GND")
		)
		(pad "215" smd rect
			(at 2.050034 -3.824986 90)
			(size 0.519938 1.4986)
			(layers "F.Cu" "F.Mask" "F.Paste")
			(net "M_G_CPU1_SA_CA<5>")
		)
		(pad "216" smd rect
			(at 2.050034 -2.975102 90)
			(size 0.519938 1.4986)
			(layers "F.Cu" "F.Mask" "F.Paste")
			(net "GND")
		)
		(pad "217" smd rect
			(at 2.050034 -2.124964 90)
			(size 0.519938 1.4986)
			(layers "F.Cu" "F.Mask" "F.Paste")
			(net "M_G_CPU1_CLK_DP<0>")
		)
		(pad "218" smd rect
			(at 2.050034 -1.27508 90)
			(size 0.519938 1.4986)
			(layers "F.Cu" "F.Mask" "F.Paste")
			(net "M_G_CPU1_CLK_DN<0>")
		)
		(pad "219" smd rect
			(at 2.050034 -0.424942 90)
			(size 0.519938 1.4986)
			(layers "F.Cu" "F.Mask" "F.Paste")
			(net "GND")
		)
		(pad "220" smd rect
			(at 2.050034 5.525008 90)
			(size 0.519938 1.4986)
			(layers "F.Cu" "F.Mask" "F.Paste")
			(net "Net_2344")
		)
		(pad "221" smd rect
			(at 2.050034 6.374892 90)
			(size 0.519938 1.4986)
			(layers "F.Cu" "F.Mask" "F.Paste")
			(net "M_G_CPU1_SB_CA<1>")
		)
		(pad "222" smd rect
			(at 2.050034 7.22503 90)
			(size 0.519938 1.4986)
			(layers "F.Cu" "F.Mask" "F.Paste")
			(net "GND")
		)
		(pad "223" smd rect
			(at 2.050034 8.074914 90)
			(size 0.519938 1.4986)
			(layers "F.Cu" "F.Mask" "F.Paste")
			(net "M_G_CPU1_SB_CA<3>")
		)
		(pad "224" smd rect
			(at 2.050034 8.925052 90)
			(size 0.519938 1.4986)
			(layers "F.Cu" "F.Mask" "F.Paste")
			(net "GND")
		)
		(pad "225" smd rect
			(at 2.050034 9.774936 90)
			(size 0.519938 1.4986)
			(layers "F.Cu" "F.Mask" "F.Paste")
			(net "M_G_CPU1_SB_CA<5>")
		)
		(pad "226" smd rect
			(at 2.050034 10.625074 90)
			(size 0.519938 1.4986)
			(layers "F.Cu" "F.Mask" "F.Paste")
			(net "GND")
		)
	)
)
